# SCM (Grand Teton) — schematic netlist excerpt (pin names and nets, part order shuffled) for the footprints in the layout excerpt that follows; sources: Cadence DE-HDL packaged netlist, KiCad conversion of 12092022_DA0F0TMDCD0_F0T_Management_Board_D_brd_V3_OCP.brd

J17  PICOPROBE_BXA  DELTA-L 4.0 EMPTY  pkg TRIANG_LAUNCH_3PXB  page 58
  \1_p\  = 85_5INCH_BOT_DN
  \2_n\  = 85_5INCH_BOT_DP
  \3_g\  = GND_P1

(kicad_pcb
	(version 20260206)
	(generator "pcbnew")
	(generator_version "10.0")
	(general
		(thickness 1.6)
		(legacy_teardrops no)
	)
	(paper "A4")
	(title_block
		(title "12092022_DA0F0TMDCD0_F0T_Management_Board_D_brd_V3_OCP.brd")
		(comment 1 "Grand Teton / footprints 1058-1058 of 1440")
	)
	(layers
		(0 "F.Cu" signal "TOP")
		(4 "In1.Cu" signal "GND")
		(6 "In2.Cu" signal "IN1")
		(8 "In3.Cu" signal "GND1")
		(10 "In4.Cu" signal "IN2")
		(12 "In5.Cu" signal "VCC")
		(14 "In6.Cu" signal "VCC1")
		(16 "In7.Cu" signal "IN3")
		(18 "In8.Cu" signal "GND2")
		(20 "In9.Cu" signal "IN4")
		(22 "In10.Cu" signal "GND3")
		(2 "B.Cu" signal "BOTTOM")
		(9 "F.Adhes" user "F.Adhesive")
		(11 "B.Adhes" user "B.Adhesive")
		(13 "F.Paste" user "Package Geometry/Pastemask Top")
		(15 "B.Paste" user "Package Geometry/Pastemask Bottom")
		(5 "F.SilkS" user "Ref Des/Silkscreen Top")
		(7 "B.SilkS" user "Ref Des/Silkscreen Bottom")
		(1 "F.Mask" user "Board Geometry/Soldermask Top")
		(3 "B.Mask" user "Board Geometry/Soldermask Bottom")
		(17 "Dwgs.User" user "User.Drawings")
		(19 "Cmts.User" user "User.Comments")
		(21 "Eco1.User" user "User.Eco1")
		(23 "Eco2.User" user "User.Eco2")
		(25 "Edge.Cuts" user "Board Geometry/Outline")
		(27 "Margin" user)
		(31 "F.CrtYd" user "Package Geometry/Place Bound Top")
		(29 "B.CrtYd" user "Package Geometry/Place Bound Bottom")
		(35 "F.Fab" user "Ref Des/Assembly Top")
		(33 "B.Fab" user "Ref Des/Assembly Bottom")
	)
	(footprint ""
		(layer "B.Cu")
		(at 103.8225 -104.76484 90)
		(property "Reference" "J17"
			(at -0.87884 2.95783 270)
			(unlocked yes)
			(layer "B.SilkS")
			(effects
				(font
					(size 0.7874 0.5842)
					(thickness 0.1524)
				)
				(justify left mirror)
			)
		)
		(property "Value" ""
			(at 0 0 90)
			(layer "B.Fab")
			(effects
				(font
					(size 1.27 1.27)
				)
				(justify mirror)
			)
		)
		(duplicate_pad_numbers_are_jumpers no)
		(fp_line
			(start 1.2192 -2.1082)
			(end -1.2192 -2.1082)
			(stroke
				(width 0.1524)
				(type default)
			)
			(layer "B.SilkS")
		)
		(fp_line
			(start -1.2192 -2.1082)
			(end -1.2192 -0.456184)
			(stroke
				(width 0.1524)
				(type default)
			)
			(layer "B.SilkS")
		)
		(fp_line
			(start -1.2192 0.451104)
			(end -1.2192 2.1082)
			(stroke
				(width 0.1524)
				(type default)
			)
			(layer "B.SilkS")
		)
		(fp_line
			(start 1.2192 2.1082)
			(end 1.2192 -2.1082)
			(stroke
				(width 0.1524)
				(type default)
			)
			(layer "B.SilkS")
		)
		(fp_line
			(start -1.2192 2.1082)
			(end 1.2192 2.1082)
			(stroke
				(width 0.1524)
				(type default)
			)
			(layer "B.SilkS")
		)
		(pad "" np_thru_hole circle
			(at -3.4671 -1.27)
			(size 1.0414 1.0414)
			(drill 1.0414)
			(layers "*.Cu" "*.Mask")
			(clearance 0.381)
			(thermal_gap 0.381)
		)
		(pad "" np_thru_hole circle
			(at -3.4671 1.27)
			(size 1.0414 1.0414)
			(drill 1.0414)
			(layers "*.Cu" "*.Mask")
			(clearance 0.381)
			(thermal_gap 0.381)
		)
		(pad "" np_thru_hole circle
			(at 2.8829 -1.27)
			(size 1.0414 1.0414)
			(drill 1.0414)
			(layers "*.Cu" "*.Mask")
			(clearance 0.381)
			(thermal_gap 0.381)
		)
		(pad "" np_thru_hole circle
			(at 2.8829 1.27)
			(size 1.0414 1.0414)
			(drill 1.0414)
			(layers "*.Cu" "*.Mask")
			(clearance 0.381)
			(thermal_gap 0.381)
		)
		(pad "1" smd rect
			(at -0.8255 -0.249936)
			(size 0.3048 0.508)
			(layers "B.Cu" "B.Mask" "B.Paste")
			(net "85_5INCH_BOT_DN")
		)
		(pad "2" smd rect
			(at -0.8255 0.249936)
			(size 0.3048 0.508)
			(layers "B.Cu" "B.Mask" "B.Paste")
			(net "85_5INCH_BOT_DP")
		)
		(pad "3" smd circle
			(at 0 0 270)
			(size 0 0)
			(layers "B.Cu" "B.Mask" "B.Paste")
			(net "GND_P1")
		)
		(zone
			(layers "F.Cu" "B.Cu" "In1.Cu" "In2.Cu" "In3.Cu" "In4.Cu" "In5.Cu" "In6.Cu"
				"In7.Cu" "In8.Cu" "In9.Cu" "In10.Cu"
			)
			(hatch none 0.5)
			(connect_pads
				(clearance 0)
			)
			(min_thickness 0.25)
			(keepout
				(tracks not_allowed)
				(vias allowed)
				(pads allowed)
				(copperpour not_allowed)
				(footprints allowed)
			)
			(placement
				(enabled no)
				(sheetname "")
			)
			(fill
				(thermal_gap 0.5)
				(thermal_bridge_width 0.5)
				(island_removal_mode 0)
			)
			(polygon
				(pts
					(arc
						(start 103.4796 -107.64774)
						(mid 101.6254 -107.64774)
						(end 103.4796 -107.64774)
					)
				)
			)
		)
		(zone
			(layers "F.Cu" "B.Cu" "In1.Cu" "In2.Cu" "In3.Cu" "In4.Cu" "In5.Cu" "In6.Cu"
				"In7.Cu" "In8.Cu" "In9.Cu" "In10.Cu"
			)
			(hatch none 0.5)
			(connect_pads
				(clearance 0)
			)
			(min_thickness 0.25)
			(keepout
				(tracks not_allowed)
				(vias allowed)
				(pads allowed)
				(copperpour not_allowed)
				(footprints allowed)
			)
			(placement
				(enabled no)
				(sheetname "")
			)
			(fill
				(thermal_gap 0.5)
				(thermal_bridge_width 0.5)
				(island_removal_mode 0)
			)
			(polygon
				(pts
					(arc
						(start 103.4796 -101.29774)
						(mid 101.6254 -101.29774)
						(end 103.4796 -101.29774)
					)
				)
			)
		)
		(zone
			(layers "F.Cu" "B.Cu" "In1.Cu" "In2.Cu" "In3.Cu" "In4.Cu" "In5.Cu" "In6.Cu"
				"In7.Cu" "In8.Cu" "In9.Cu" "In10.Cu"
			)
			(hatch none 0.5)
			(connect_pads
				(clearance 0)
			)
			(min_thickness 0.25)
			(keepout
				(tracks not_allowed)
				(vias allowed)
				(pads allowed)
				(copperpour not_allowed)
				(footprints allowed)
			)
			(placement
				(enabled no)
				(sheetname "")
			)
			(fill
				(thermal_gap 0.5)
				(thermal_bridge_width 0.5)
				(island_removal_mode 0)
			)
			(polygon
				(pts
					(arc
						(start 106.0196 -107.64774)
						(mid 104.1654 -107.64774)
						(end 106.0196 -107.64774)
					)
				)
			)
		)
		(zone
			(layers "F.Cu" "B.Cu" "In1.Cu" "In2.Cu" "In3.Cu" "In4.Cu" "In5.Cu" "In6.Cu"
				"In7.Cu" "In8.Cu" "In9.Cu" "In10.Cu"
			)
			(hatch none 0.5)
			(connect_pads
				(clearance 0)
			)
			(min_thickness 0.25)
			(keepout
				(tracks not_allowed)
				(vias allowed)
				(pads allowed)
				(copperpour not_allowed)
				(footprints allowed)
			)
			(placement
				(enabled no)
				(sheetname "")
			)
			(fill
				(thermal_gap 0.5)
				(thermal_bridge_width 0.5)
				(island_removal_mode 0)
			)
			(polygon
				(pts
					(arc
						(start 106.0196 -101.29774)
						(mid 104.1654 -101.29774)
						(end 106.0196 -101.29774)
					)
				)
			)
		)
		(zone
			(layer "B.Cu")
			(hatch none 0.5)
			(connect_pads
				(clearance 0)
			)
			(min_thickness 0.25)
			(keepout
				(tracks not_allowed)
				(vias allowed)
				(pads allowed)
				(copperpour not_allowed)
				(footprints allowed)
			)
			(placement
				(enabled no)
				(sheetname "")
			)
			(fill
				(thermal_gap 0.5)
				(thermal_bridge_width 0.5)
				(island_removal_mode 0)
			)
			(polygon
				(pts
					(xy 103.27386 -103.64724) (xy 103.369364 -103.64724) (xy 103.369364 -104.24414) (xy 103.775764 -104.24414)
					(xy 103.775764 -103.64724) (xy 103.869236 -103.64724) (xy 103.869236 -104.24414) (xy 104.275636 -104.24414)
					(xy 104.275636 -103.64724) (xy 104.37114 -103.64724) (xy 104.37114 -104.34574) (xy 103.27386 -104.34574)
				)
			)
		)
	)
)
